(kicad_pcb
	(version 20260206)
	(generator "pcbnew")
	(generator_version "10.0")
	(general
		(thickness 1.6)
		(legacy_teardrops no)
	)
	(paper "A4")
	(title_block
		(title "v1-chassis-manager — T6M_CM_d_v01_1031_1645.brd")
		(comment 1 "Open CloudServer (Microsoft) / footprints 2263-2273 of 2512")
	)
	(layers
		(0 "F.Cu" signal "TOP")
		(4 "In1.Cu" signal "GND1")
		(6 "In2.Cu" signal "IN1")
		(8 "In3.Cu" signal "VCC1")
		(10 "In4.Cu" signal "VCC2")
		(12 "In5.Cu" signal "GND2")
		(14 "In6.Cu" signal "IN2")
		(16 "In7.Cu" signal "IN3")
		(18 "In8.Cu" signal "GND3")
		(2 "B.Cu" signal "BOTTOM")
		(9 "F.Adhes" user "F.Adhesive")
		(11 "B.Adhes" user "B.Adhesive")
		(13 "F.Paste" user "Package Geometry/Pastemask Top")
		(15 "B.Paste" user "Package Geometry/Pastemask Bottom")
		(5 "F.SilkS" user "Ref Des/Silkscreen Top")
		(7 "B.SilkS" user "Ref Des/Silkscreen Bottom")
		(1 "F.Mask" user "Board Geometry/Soldermask Top")
		(3 "B.Mask" user "Board Geometry/Soldermask Bottom")
		(17 "Dwgs.User" user "User.Drawings")
		(19 "Cmts.User" user "User.Comments")
		(21 "Eco1.User" user "User.Eco1")
		(23 "Eco2.User" user "User.Eco2")
		(25 "Edge.Cuts" user "Board Geometry/Outline")
		(27 "Margin" user)
		(31 "F.CrtYd" user "Package Geometry/Place Bound Top")
		(29 "B.CrtYd" user "Package Geometry/Place Bound Bottom")
		(35 "F.Fab" user "Ref Des/Assembly Top")
		(33 "B.Fab" user "Ref Des/Assembly Bottom")
	)
	(footprint ""
		(layer "B.Cu")
		(at 69.326252 -135.489188 180)
		(property "Reference" "C281"
			(at 35.998912 -52.76469 0)
			(unlocked yes)
			(layer "B.SilkS")
			(effects
				(font
					(size 0.7874 0.5842)
					(thickness 0.1524)
				)
				(justify left mirror)
			)
		)
		(property "Value" ""
			(at 0 0 0)
			(layer "B.Fab")
			(effects
				(font
					(size 1.27 1.27)
				)
				(justify mirror)
			)
		)
		(duplicate_pad_numbers_are_jumpers no)
		(fp_line
			(start 0.7874 0.4064)
			(end 0.7874 -0.4064)
			(stroke
				(width 0.1524)
				(type default)
			)
			(layer "B.SilkS")
		)
		(fp_line
			(start 0.7874 -0.4064)
			(end -0.7874 -0.4064)
			(stroke
				(width 0.1524)
				(type default)
			)
			(layer "B.SilkS")
		)
		(fp_line
			(start 0 0.381)
			(end 0 -0.381)
			(stroke
				(width 0.1524)
				(type default)
			)
			(layer "B.SilkS")
		)
		(fp_line
			(start -0.7874 0.4064)
			(end 0.7874 0.4064)
			(stroke
				(width 0.1524)
				(type default)
			)
			(layer "B.SilkS")
		)
		(fp_line
			(start -0.7874 -0.4064)
			(end -0.7874 0.4064)
			(stroke
				(width 0.1524)
				(type default)
			)
			(layer "B.SilkS")
		)
		(fp_poly
			(pts
				(xy 0.5334 0.254) (xy 0.635 0.254) (xy 0.635 0.2286) (xy 0.635 -0.254) (xy 0.5334 -0.254) (xy 0.5334 -0.2794)
				(xy -0.5334 -0.2794) (xy -0.5334 -0.254) (xy -0.635 -0.254) (xy -0.635 0.254) (xy -0.5334 0.254)
				(xy -0.5334 0.2794) (xy 0.508 0.2794) (xy 0.5334 0.2794)
			)
			(stroke
				(width 0)
				(type default)
			)
			(fill no)
			(layer "B.CrtYd")
		)
		(pad "1" smd rect
			(at -0.40005 0)
			(size 0.4572 0.508)
			(layers "B.Cu" "B.Mask" "B.Paste")
			(net "P3V3_NODE1")
		)
		(pad "2" smd rect
			(at 0.40005 0)
			(size 0.4572 0.508)
			(layers "B.Cu" "B.Mask" "B.Paste")
			(net "GND")
		)
	)
	(footprint ""
		(layer "B.Cu")
		(at 78.83144 -176.569624 180)
		(property "Reference" "R695"
			(at -30.562296 -20.108164 0)
			(unlocked yes)
			(layer "B.SilkS")
			(effects
				(font
					(size 0.7874 0.5842)
					(thickness 0.1524)
				)
				(justify left mirror)
			)
		)
		(property "Value" ""
			(at 0 0 0)
			(layer "B.Fab")
			(effects
				(font
					(size 1.27 1.27)
				)
				(justify mirror)
			)
		)
		(duplicate_pad_numbers_are_jumpers no)
		(fp_line
			(start 0.7874 0.4064)
			(end 0.7874 -0.4064)
			(stroke
				(width 0.1524)
				(type default)
			)
			(layer "B.SilkS")
		)
		(fp_line
			(start 0.7874 -0.4064)
			(end -0.7874 -0.4064)
			(stroke
				(width 0.1524)
				(type default)
			)
			(layer "B.SilkS")
		)
		(fp_line
			(start -0.7874 0.4064)
			(end 0.7874 0.4064)
			(stroke
				(width 0.1524)
				(type default)
			)
			(layer "B.SilkS")
		)
		(fp_line
			(start -0.7874 -0.4064)
			(end -0.7874 0.4064)
			(stroke
				(width 0.1524)
				(type default)
			)
			(layer "B.SilkS")
		)
		(fp_poly
			(pts
				(xy 0.508 0.2794) (xy 0.508 0.2286) (xy 0.635 0.2286) (xy 0.635 -0.254) (xy 0.5334 -0.254) (xy 0.5334 -0.2794)
				(xy -0.5334 -0.2794) (xy -0.5334 -0.254) (xy -0.635 -0.254) (xy -0.635 0.254) (xy -0.5334 0.254)
				(xy -0.5334 0.2794)
			)
			(stroke
				(width 0)
				(type default)
			)
			(fill no)
			(layer "B.CrtYd")
		)
		(pad "1" smd rect
			(at -0.40005 0)
			(size 0.4572 0.508)
			(layers "B.Cu" "B.Mask" "B.Paste")
			(net "T2_NODE3_EN")
		)
		(pad "2" smd rect
			(at 0.40005 0)
			(size 0.4572 0.508)
			(layers "B.Cu" "B.Mask" "B.Paste")
			(net "P5V_NODE1")
		)
	)
	(footprint ""
		(layer "B.Cu")
		(at 130.79476 -187.872624 90)
		(property "Reference" "R968"
			(at 4.565396 -1.054354 270)
			(unlocked yes)
			(layer "B.SilkS")
			(effects
				(font
					(size 0.7874 0.5842)
					(thickness 0.1524)
				)
				(justify left mirror)
			)
		)
		(property "Value" ""
			(at 0 0 90)
			(layer "B.Fab")
			(effects
				(font
					(size 1.27 1.27)
				)
				(justify mirror)
			)
		)
		(duplicate_pad_numbers_are_jumpers no)
		(fp_line
			(start 0.7874 -0.4064)
			(end -0.7874 -0.4064)
			(stroke
				(width 0.1524)
				(type default)
			)
			(layer "B.SilkS")
		)
		(fp_line
			(start -0.7874 -0.4064)
			(end -0.7874 0.4064)
			(stroke
				(width 0.1524)
				(type default)
			)
			(layer "B.SilkS")
		)
		(fp_line
			(start 0.7874 0.4064)
			(end 0.7874 -0.4064)
			(stroke
				(width 0.1524)
				(type default)
			)
			(layer "B.SilkS")
		)
		(fp_line
			(start -0.7874 0.4064)
			(end 0.7874 0.4064)
			(stroke
				(width 0.1524)
				(type default)
			)
			(layer "B.SilkS")
		)
		(fp_poly
			(pts
				(xy 0.508 0.2794) (xy 0.508 0.2286) (xy 0.635 0.2286) (xy 0.635 -0.254) (xy 0.5334 -0.254) (xy 0.5334 -0.2794)
				(xy -0.5334 -0.2794) (xy -0.5334 -0.254) (xy -0.635 -0.254) (xy -0.635 0.254) (xy -0.5334 0.254)
				(xy -0.5334 0.2794)
			)
			(stroke
				(width 0)
				(type default)
			)
			(fill no)
			(layer "B.CrtYd")
		)
		(pad "1" smd rect
			(at -0.40005 0 270)
			(size 0.4572 0.508)
			(layers "B.Cu" "B.Mask" "B.Paste")
			(net "UART_T9_NODE3_RXD")
		)
		(pad "2" smd rect
			(at 0.40005 0 270)
			(size 0.4572 0.508)
			(layers "B.Cu" "B.Mask" "B.Paste")
			(net "UART_T9_NODE3_RXD_R")
		)
	)
	(footprint ""
		(layer "B.Cu")
		(at 66.214498 -96.696784 90)
		(property "Reference" "R152"
			(at 6.314948 -4.996688 270)
			(unlocked yes)
			(layer "B.SilkS")
			(effects
				(font
					(size 0.7874 0.5842)
					(thickness 0.1524)
				)
				(justify left mirror)
			)
		)
		(property "Value" ""
			(at 0 0 90)
			(layer "B.Fab")
			(effects
				(font
					(size 1.27 1.27)
				)
				(justify mirror)
			)
		)
		(duplicate_pad_numbers_are_jumpers no)
		(fp_line
			(start 0.7874 -0.4064)
			(end -0.7874 -0.4064)
			(stroke
				(width 0.1524)
				(type default)
			)
			(layer "B.SilkS")
		)
		(fp_line
			(start -0.7874 -0.4064)
			(end -0.7874 0.4064)
			(stroke
				(width 0.1524)
				(type default)
			)
			(layer "B.SilkS")
		)
		(fp_line
			(start 0.7874 0.4064)
			(end 0.7874 -0.4064)
			(stroke
				(width 0.1524)
				(type default)
			)
			(layer "B.SilkS")
		)
		(fp_line
			(start -0.7874 0.4064)
			(end 0.7874 0.4064)
			(stroke
				(width 0.1524)
				(type default)
			)
			(layer "B.SilkS")
		)
		(fp_poly
			(pts
				(xy 0.508 0.2794) (xy 0.508 0.2286) (xy 0.635 0.2286) (xy 0.635 -0.254) (xy 0.5334 -0.254) (xy 0.5334 -0.2794)
				(xy -0.5334 -0.2794) (xy -0.5334 -0.254) (xy -0.635 -0.254) (xy -0.635 0.254) (xy -0.5334 0.254)
				(xy -0.5334 0.2794)
			)
			(stroke
				(width 0)
				(type default)
			)
			(fill no)
			(layer "B.CrtYd")
		)
		(pad "1" smd rect
			(at -0.40005 0 270)
			(size 0.4572 0.508)
			(layers "B.Cu" "B.Mask" "B.Paste")
			(net "PD_CPU_NODE1_BRD_ID1")
		)
		(pad "2" smd rect
			(at 0.40005 0 270)
			(size 0.4572 0.508)
			(layers "B.Cu" "B.Mask" "B.Paste")
			(net "P3V3_NODE1")
		)
	)
	(footprint ""
		(layer "B.Cu")
		(at 110.44936 -172.505624)
		(property "Reference" "R702"
			(at -21.356828 32.314642 0)
			(unlocked yes)
			(layer "B.SilkS")
			(effects
				(font
					(size 0.7874 0.5842)
					(thickness 0.1524)
				)
				(justify left mirror)
			)
		)
		(property "Value" ""
			(at 0 0 0)
			(layer "B.Fab")
			(effects
				(font
					(size 1.27 1.27)
				)
				(justify mirror)
			)
		)
		(duplicate_pad_numbers_are_jumpers no)
		(fp_line
			(start -0.7874 -0.4064)
			(end -0.7874 0.4064)
			(stroke
				(width 0.1524)
				(type default)
			)
			(layer "B.SilkS")
		)
		(fp_line
			(start -0.7874 0.4064)
			(end 0.7874 0.4064)
			(stroke
				(width 0.1524)
				(type default)
			)
			(layer "B.SilkS")
		)
		(fp_line
			(start 0.7874 -0.4064)
			(end -0.7874 -0.4064)
			(stroke
				(width 0.1524)
				(type default)
			)
			(layer "B.SilkS")
		)
		(fp_line
			(start 0.7874 0.4064)
			(end 0.7874 -0.4064)
			(stroke
				(width 0.1524)
				(type default)
			)
			(layer "B.SilkS")
		)
		(fp_poly
			(pts
				(xy 0.508 0.2794) (xy 0.508 0.2286) (xy 0.635 0.2286) (xy 0.635 -0.254) (xy 0.5334 -0.254) (xy 0.5334 -0.2794)
				(xy -0.5334 -0.2794) (xy -0.5334 -0.254) (xy -0.635 -0.254) (xy -0.635 0.254) (xy -0.5334 0.254)
				(xy -0.5334 0.2794)
			)
			(stroke
				(width 0)
				(type default)
			)
			(fill no)
			(layer "B.CrtYd")
		)
		(pad "1" smd rect
			(at -0.40005 0 180)
			(size 0.4572 0.508)
			(layers "B.Cu" "B.Mask" "B.Paste")
			(net "P3V3_NODE1")
		)
		(pad "2" smd rect
			(at 0.40005 0 180)
			(size 0.4572 0.508)
			(layers "B.Cu" "B.Mask" "B.Paste")
			(net "N21699571")
		)
	)
	(footprint ""
		(layer "B.Cu")
		(at 165.011608 -183.051196)
		(property "Reference" "R1173"
			(at 6.724904 -9.022588 0)
			(unlocked yes)
			(layer "B.SilkS")
			(effects
				(font
					(size 0.7874 0.5842)
					(thickness 0.1524)
				)
				(justify left mirror)
			)
		)
		(property "Value" ""
			(at 0 0 0)
			(layer "B.Fab")
			(effects
				(font
					(size 1.27 1.27)
				)
				(justify mirror)
			)
		)
		(duplicate_pad_numbers_are_jumpers no)
		(fp_line
			(start -0.7874 -0.406146)
			(end -0.7874 0.406146)
			(stroke
				(width 0.1524)
				(type default)
			)
			(layer "B.SilkS")
		)
		(fp_line
			(start -0.7874 0.406146)
			(end 0.7874 0.406146)
			(stroke
				(width 0.1524)
				(type default)
			)
			(layer "B.SilkS")
		)
		(fp_line
			(start 0.7874 -0.406146)
			(end -0.7874 -0.406146)
			(stroke
				(width 0.1524)
				(type default)
			)
			(layer "B.SilkS")
		)
		(fp_line
			(start 0.7874 0.406146)
			(end 0.7874 -0.406146)
			(stroke
				(width 0.1524)
				(type default)
			)
			(layer "B.SilkS")
		)
		(fp_poly
			(pts
				(xy 0.508 0.2794) (xy 0.508 0.2286) (xy 0.635 0.2286) (xy 0.635 -0.254) (xy 0.5334 -0.254) (xy 0.5334 -0.2794)
				(xy -0.5334 -0.2794) (xy -0.5334 -0.254) (xy -0.635 -0.254) (xy -0.635 0.254) (xy -0.5334 0.254)
				(xy -0.5334 0.2794)
			)
			(stroke
				(width 0)
				(type default)
			)
			(fill no)
			(layer "B.CrtYd")
		)
		(pad "1" smd rect
			(at -0.40005 0 180)
			(size 0.4572 0.508)
			(layers "B.Cu" "B.Mask" "B.Paste")
			(net "CPLD_UART_RX_P4_R")
		)
		(pad "2" smd rect
			(at 0.40005 0 180)
			(size 0.4572 0.508)
			(layers "B.Cu" "B.Mask" "B.Paste")
			(net "CPLD_UART_RX_P4")
		)
	)
	(footprint ""
		(layer "B.Cu")
		(at 57.345072 -126.518162 180)
		(property "Reference" "R294"
			(at 39.74211 -52.083208 0)
			(unlocked yes)
			(layer "B.SilkS")
			(effects
				(font
					(size 0.7874 0.5842)
					(thickness 0.1524)
				)
				(justify left mirror)
			)
		)
		(property "Value" ""
			(at 0 0 0)
			(layer "B.Fab")
			(effects
				(font
					(size 1.27 1.27)
				)
				(justify mirror)
			)
		)
		(duplicate_pad_numbers_are_jumpers no)
		(fp_line
			(start 0.7874 0.4064)
			(end 0.7874 -0.4064)
			(stroke
				(width 0.1524)
				(type default)
			)
			(layer "B.SilkS")
		)
		(fp_line
			(start 0.7874 -0.4064)
			(end -0.7874 -0.4064)
			(stroke
				(width 0.1524)
				(type default)
			)
			(layer "B.SilkS")
		)
		(fp_line
			(start -0.7874 0.4064)
			(end 0.7874 0.4064)
			(stroke
				(width 0.1524)
				(type default)
			)
			(layer "B.SilkS")
		)
		(fp_line
			(start -0.7874 -0.4064)
			(end -0.7874 0.4064)
			(stroke
				(width 0.1524)
				(type default)
			)
			(layer "B.SilkS")
		)
		(fp_poly
			(pts
				(xy 0.508 0.2794) (xy 0.508 0.2286) (xy 0.635 0.2286) (xy 0.635 -0.254) (xy 0.5334 -0.254) (xy 0.5334 -0.2794)
				(xy -0.5334 -0.2794) (xy -0.5334 -0.254) (xy -0.635 -0.254) (xy -0.635 0.254) (xy -0.5334 0.254)
				(xy -0.5334 0.2794)
			)
			(stroke
				(width 0)
				(type default)
			)
			(fill no)
			(layer "B.CrtYd")
		)
		(pad "1" smd rect
			(at -0.40005 0)
			(size 0.4572 0.508)
			(layers "B.Cu" "B.Mask" "B.Paste")
			(net "BMC_NODE1_USBVREF")
		)
		(pad "2" smd rect
			(at 0.40005 0)
			(size 0.4572 0.508)
			(layers "B.Cu" "B.Mask" "B.Paste")
			(net "GND")
		)
	)
	(footprint ""
		(layer "B.Cu")
		(at 90.81262 -169.958512)
		(property "Reference" "R687"
			(at 24.81707 20.071588 0)
			(unlocked yes)
			(layer "B.SilkS")
			(effects
				(font
					(size 0.7874 0.5842)
					(thickness 0.1524)
				)
				(justify left mirror)
			)
		)
		(property "Value" ""
			(at 0 0 0)
			(layer "B.Fab")
			(effects
				(font
					(size 1.27 1.27)
				)
				(justify mirror)
			)
		)
		(duplicate_pad_numbers_are_jumpers no)
		(fp_line
			(start -0.7874 -0.4064)
			(end -0.7874 0.4064)
			(stroke
				(width 0.1524)
				(type default)
			)
			(layer "B.SilkS")
		)
		(fp_line
			(start -0.7874 0.4064)
			(end 0.7874 0.4064)
			(stroke
				(width 0.1524)
				(type default)
			)
			(layer "B.SilkS")
		)
		(fp_line
			(start 0.7874 -0.4064)
			(end -0.7874 -0.4064)
			(stroke
				(width 0.1524)
				(type default)
			)
			(layer "B.SilkS")
		)
		(fp_line
			(start 0.7874 0.4064)
			(end 0.7874 -0.4064)
			(stroke
				(width 0.1524)
				(type default)
			)
			(layer "B.SilkS")
		)
		(fp_poly
			(pts
				(xy 0.508 0.2794) (xy 0.508 0.2286) (xy 0.635 0.2286) (xy 0.635 -0.254) (xy 0.5334 -0.254) (xy 0.5334 -0.2794)
				(xy -0.5334 -0.2794) (xy -0.5334 -0.254) (xy -0.635 -0.254) (xy -0.635 0.254) (xy -0.5334 0.254)
				(xy -0.5334 0.2794)
			)
			(stroke
				(width 0)
				(type default)
			)
			(fill no)
			(layer "B.CrtYd")
		)
		(pad "1" smd rect
			(at -0.40005 0 180)
			(size 0.4572 0.508)
			(layers "B.Cu" "B.Mask" "B.Paste")
			(net "N21700927")
		)
		(pad "2" smd rect
			(at 0.40005 0 180)
			(size 0.4572 0.508)
			(layers "B.Cu" "B.Mask" "B.Paste")
			(net "GND")
		)
	)
	(footprint ""
		(layer "B.Cu")
		(at 110.44936 -175.553624 180)
		(property "Reference" "R711"
			(at 21.356828 -32.269176 0)
			(unlocked yes)
			(layer "B.SilkS")
			(effects
				(font
					(size 0.7874 0.5842)
					(thickness 0.1524)
				)
				(justify left mirror)
			)
		)
		(property "Value" ""
			(at 0 0 0)
			(layer "B.Fab")
			(effects
				(font
					(size 1.27 1.27)
				)
				(justify mirror)
			)
		)
		(duplicate_pad_numbers_are_jumpers no)
		(fp_line
			(start 0.7874 0.4064)
			(end 0.7874 -0.4064)
			(stroke
				(width 0.1524)
				(type default)
			)
			(layer "B.SilkS")
		)
		(fp_line
			(start 0.7874 -0.4064)
			(end -0.7874 -0.4064)
			(stroke
				(width 0.1524)
				(type default)
			)
			(layer "B.SilkS")
		)
		(fp_line
			(start -0.7874 0.4064)
			(end 0.7874 0.4064)
			(stroke
				(width 0.1524)
				(type default)
			)
			(layer "B.SilkS")
		)
		(fp_line
			(start -0.7874 -0.4064)
			(end -0.7874 0.4064)
			(stroke
				(width 0.1524)
				(type default)
			)
			(layer "B.SilkS")
		)
		(fp_poly
			(pts
				(xy 0.508 0.2794) (xy 0.508 0.2286) (xy 0.635 0.2286) (xy 0.635 -0.254) (xy 0.5334 -0.254) (xy 0.5334 -0.2794)
				(xy -0.5334 -0.2794) (xy -0.5334 -0.254) (xy -0.635 -0.254) (xy -0.635 0.254) (xy -0.5334 0.254)
				(xy -0.5334 0.2794)
			)
			(stroke
				(width 0)
				(type default)
			)
			(fill no)
			(layer "B.CrtYd")
		)
		(pad "1" smd rect
			(at -0.40005 0)
			(size 0.4572 0.508)
			(layers "B.Cu" "B.Mask" "B.Paste")
			(net "T5_NODE2_EN")
		)
		(pad "2" smd rect
			(at 0.40005 0)
			(size 0.4572 0.508)
			(layers "B.Cu" "B.Mask" "B.Paste")
			(net "P5V_NODE1")
		)
	)
	(footprint ""
		(layer "B.Cu")
		(at 78.62062 -185.259218 90)
		(property "Reference" "R886"
			(at 3.798062 0.041148 270)
			(unlocked yes)
			(layer "B.SilkS")
			(effects
				(font
					(size 0.7874 0.5842)
					(thickness 0.1524)
				)
				(justify left mirror)
			)
		)
		(property "Value" ""
			(at 0 0 90)
			(layer "B.Fab")
			(effects
				(font
					(size 1.27 1.27)
				)
				(justify mirror)
			)
		)
		(duplicate_pad_numbers_are_jumpers no)
		(fp_line
			(start 0.7874 -0.4064)
			(end -0.7874 -0.4064)
			(stroke
				(width 0.1524)
				(type default)
			)
			(layer "B.SilkS")
		)
		(fp_line
			(start -0.7874 -0.4064)
			(end -0.7874 0.4064)
			(stroke
				(width 0.1524)
				(type default)
			)
			(layer "B.SilkS")
		)
		(fp_line
			(start 0.7874 0.4064)
			(end 0.7874 -0.4064)
			(stroke
				(width 0.1524)
				(type default)
			)
			(layer "B.SilkS")
		)
		(fp_line
			(start -0.7874 0.4064)
			(end 0.7874 0.4064)
			(stroke
				(width 0.1524)
				(type default)
			)
			(layer "B.SilkS")
		)
		(fp_poly
			(pts
				(xy 0.508 0.2794) (xy 0.508 0.2286) (xy 0.635 0.2286) (xy 0.635 -0.254) (xy 0.5334 -0.254) (xy 0.5334 -0.2794)
				(xy -0.5334 -0.2794) (xy -0.5334 -0.254) (xy -0.635 -0.254) (xy -0.635 0.254) (xy -0.5334 0.254)
				(xy -0.5334 0.2794)
			)
			(stroke
				(width 0)
				(type default)
			)
			(fill no)
			(layer "B.CrtYd")
		)
		(pad "1" smd rect
			(at -0.40005 0 270)
			(size 0.4572 0.508)
			(layers "B.Cu" "B.Mask" "B.Paste")
			(net "T3_NODE2_EN")
		)
		(pad "2" smd rect
			(at 0.40005 0 270)
			(size 0.4572 0.508)
			(layers "B.Cu" "B.Mask" "B.Paste")
			(net "T3_NODE2_EN_R")
		)
	)
	(footprint ""
		(layer "B.Cu")
		(at 115.011454 -163.24199 180)
		(property "Reference" "R795"
			(at -1.709166 -2.076196 0)
			(unlocked yes)
			(layer "B.SilkS")
			(effects
				(font
					(size 0.7874 0.5842)
					(thickness 0.1524)
				)
				(justify left mirror)
			)
		)
		(property "Value" ""
			(at 0 0 0)
			(layer "B.Fab")
			(effects
				(font
					(size 1.27 1.27)
				)
				(justify mirror)
			)
		)
		(duplicate_pad_numbers_are_jumpers no)
		(fp_line
			(start 0.7874 0.4064)
			(end 0.7874 -0.4064)
			(stroke
				(width 0.1524)
				(type default)
			)
			(layer "B.SilkS")
		)
		(fp_line
			(start 0.7874 -0.4064)
			(end -0.7874 -0.4064)
			(stroke
				(width 0.1524)
				(type default)
			)
			(layer "B.SilkS")
		)
		(fp_line
			(start -0.7874 0.4064)
			(end 0.7874 0.4064)
			(stroke
				(width 0.1524)
				(type default)
			)
			(layer "B.SilkS")
		)
		(fp_line
			(start -0.7874 -0.4064)
			(end -0.7874 0.4064)
			(stroke
				(width 0.1524)
				(type default)
			)
			(layer "B.SilkS")
		)
		(fp_poly
			(pts
				(xy 0.508 0.2794) (xy 0.508 0.2286) (xy 0.635 0.2286) (xy 0.635 -0.254) (xy 0.5334 -0.254) (xy 0.5334 -0.2794)
				(xy -0.5334 -0.2794) (xy -0.5334 -0.254) (xy -0.635 -0.254) (xy -0.635 0.254) (xy -0.5334 0.254)
				(xy -0.5334 0.2794)
			)
			(stroke
				(width 0)
				(type default)
			)
			(fill no)
			(layer "B.CrtYd")
		)
		(pad "1" smd rect
			(at -0.40005 0)
			(size 0.4572 0.508)
			(layers "B.Cu" "B.Mask" "B.Paste")
			(net "I2C_COM3_SDA_RC")
		)
		(pad "2" smd rect
			(at 0.40005 0)
			(size 0.4572 0.508)
			(layers "B.Cu" "B.Mask" "B.Paste")
			(net "I2C_COM3_SDA")
		)
	)
)
